FILE_TYPE=LIBRARY_PARTS;
primitive 'CONN8_210HP1080BR1';
  pin
    '1':
      PIN_NUMBER='(1)';
      BIDIRECTIONAL='TRUE';
      INPUT_LOAD='(-0.01,0.01)';
      OUTPUT_LOAD='(1.0,-1.0)';
    '2':
      PIN_NUMBER='(2)';
      BIDIRECTIONAL='TRUE';
      INPUT_LOAD='(-0.01,0.01)';
      OUTPUT_LOAD='(1.0,-1.0)';
    '3':
      PIN_NUMBER='(3)';
      BIDIRECTIONAL='TRUE';
      INPUT_LOAD='(-0.01,0.01)';
      OUTPUT_LOAD='(1.0,-1.0)';
    '4':
      PIN_NUMBER='(4)';
      BIDIRECTIONAL='TRUE';
      INPUT_LOAD='(-0.01,0.01)';
      OUTPUT_LOAD='(1.0,-1.0)';
    '5':
      PIN_NUMBER='(5)';
      BIDIRECTIONAL='TRUE';
      INPUT_LOAD='(-0.01,0.01)';
      OUTPUT_LOAD='(1.0,-1.0)';
    '6':
      PIN_NUMBER='(6)';
      BIDIRECTIONAL='TRUE';
      INPUT_LOAD='(-0.01,0.01)';
      OUTPUT_LOAD='(1.0,-1.0)';
    '7':
      PIN_NUMBER='(7)';
      BIDIRECTIONAL='TRUE';
      INPUT_LOAD='(-0.01,0.01)';
      OUTPUT_LOAD='(1.0,-1.0)';
    '8':
      PIN_NUMBER='(8)';
      BIDIRECTIONAL='TRUE';
      INPUT_LOAD='(-0.01,0.01)';
      OUTPUT_LOAD='(1.0,-1.0)';
  end_pin;
  body
    PART_NAME='CONN8_210HP1080BR1';
    BODY_NAME='CONN8_210HP1080BR1';
    PHYS_DES_PREFIX='J';
    CLASS='IO';
  end_body;
end_primitive;

END.
